(kicad_pcb
	(version 20241229)
	(generator "pcbnew")
	(generator_version "9.0")
	(general
		(thickness 1.6)
		(legacy_teardrops no)
	)
	(paper "A4")
	(title_block
		(title "environment-sensor")
		(comment 1 "footprints 1-7 of 109")
	)
	(layers
		(0 "F.Cu" signal)
		(4 "In1.Cu" signal)
		(6 "In2.Cu" signal)
		(2 "B.Cu" signal)
		(9 "F.Adhes" user "F.Adhesive")
		(11 "B.Adhes" user "B.Adhesive")
		(13 "F.Paste" user)
		(15 "B.Paste" user)
		(5 "F.SilkS" user "F.Silkscreen")
		(7 "B.SilkS" user "B.Silkscreen")
		(1 "F.Mask" user)
		(3 "B.Mask" user)
		(17 "Dwgs.User" user "User.Drawings")
		(19 "Cmts.User" user "User.Comments")
		(21 "Eco1.User" user "User.Eco1")
		(23 "Eco2.User" user "User.Eco2")
		(25 "Edge.Cuts" user)
		(27 "Margin" user)
		(31 "F.CrtYd" user "F.Courtyard")
		(29 "B.CrtYd" user "B.Courtyard")
		(35 "F.Fab" user)
		(33 "B.Fab" user)
	)
	(footprint "antmicro-footprints:R_0402_1005Metric"
		(layer "F.Cu")
		(at 198.5 131.4)
		(descr "Resistor SMD 0402")
		(tags "resistor SMD 0402")
		(property "Reference" "R22"
			(at 0.85 0.4 0)
			(layer "F.SilkS")
			(effects
				(font
					(size 0.7 0.7)
					(thickness 0.15)
				)
				(justify left bottom)
			)
		)
		(property "Value" "R_100R_0402"
			(at -1.011843 1.772047 0)
			(layer "F.Fab")
			(effects
				(font
					(size 0.7 0.7)
					(thickness 0.15)
				)
				(justify left bottom)
			)
		)
		(property "Description" "SMD Chip Resistor, 100 ohm, ± 1%, 62.5 mW, 0402 [1005 Metric], Thick Film, General Purpose"
			(at 0 0 0)
			(layer "F.Fab")
			(hide yes)
			(effects
				(font
					(size 1.27 1.27)
					(thickness 0.15)
				)
			)
		)
		(property "Author" "Antmicro"
			(at 0 0 0)
			(layer "F.Fab")
			(hide yes)
			(effects
				(font
					(size 1 1)
					(thickness 0.15)
				)
			)
		)
		(property "License" "Apache-2.0"
			(at 0 0 0)
			(layer "F.Fab")
			(hide yes)
			(effects
				(font
					(size 1 1)
					(thickness 0.15)
				)
			)
		)
		(property "MPN" "CR0402-FX-1000GLF"
			(at 0 0 0)
			(layer "F.Fab")
			(hide yes)
			(effects
				(font
					(size 1 1)
					(thickness 0.15)
				)
			)
		)
		(property "Manufacturer" "Bourns"
			(at 0 0 0)
			(layer "F.Fab")
			(hide yes)
			(effects
				(font
					(size 1 1)
					(thickness 0.15)
				)
			)
		)
		(property "Public" "False"
			(at 0 0 0)
			(layer "F.Fab")
			(hide yes)
			(effects
				(font
					(size 1 1)
					(thickness 0.15)
				)
			)
		)
		(property "Tolerance" "1%"
			(at 0 0 0)
			(layer "F.Fab")
			(hide yes)
			(effects
				(font
					(size 1 1)
					(thickness 0.15)
				)
			)
		)
		(property "Val" "100R"
			(at 0 0 0)
			(layer "F.Fab")
			(hide yes)
			(effects
				(font
					(size 1 1)
					(thickness 0.15)
				)
			)
		)
		(sheetfile "environment-sensor.kicad_sch")
		(attr smd exclude_from_pos_files exclude_from_bom dnp)
		(fp_rect
			(start -0.925 -0.47)
			(end 0.925 0.47)
			(stroke
				(width 0.05)
				(type default)
			)
			(fill no)
			(layer "F.CrtYd")
		)
		(fp_rect
			(start -0.5 -0.25)
			(end 0.5 0.25)
			(stroke
				(width 0.15)
				(type solid)
			)
			(fill no)
			(layer "F.Fab")
		)
		(pad "1" smd roundrect
			(at -0.48 0)
			(size 0.59 0.64)
			(layers "F.Cu" "F.Mask" "F.Paste")
			(roundrect_rratio 0.25)
			(net 48 "Net-(U3-PA9)")
			(pintype "passive")
		)
		(pad "2" smd roundrect
			(at 0.48 0)
			(size 0.59 0.64)
			(layers "F.Cu" "F.Mask" "F.Paste")
			(roundrect_rratio 0.25)
			(net 8 "I2C_1_SCL")
			(pintype "passive")
		)
	)
	(footprint "antmicro-footprints:SOD-923"
		(layer "F.Cu")
		(at 168.035 123.95 -90)
		(property "Reference" "D1"
			(at 1.1 0.535 0)
			(unlocked yes)
			(layer "F.SilkS")
			(effects
				(font
					(size 0.65 0.65)
					(thickness 0.15)
				)
			)
		)
		(property "Value" "ESD9X5.0ST5G"
			(at 0 2.4 270)
			(unlocked yes)
			(layer "F.Fab")
			(effects
				(font
					(size 1 1)
					(thickness 0.15)
				)
			)
		)
		(property "Description" "Unidirectional TVS, 30 kV,  SOD-923, 5 V, 65 pF"
			(at 0 0 270)
			(layer "F.Fab")
			(hide yes)
			(effects
				(font
					(size 1.27 1.27)
					(thickness 0.15)
				)
			)
		)
		(property "Author" "Antmicro"
			(at 44.085 291.985 0)
			(layer "F.Fab")
			(hide yes)
			(effects
				(font
					(size 1 1)
					(thickness 0.15)
				)
			)
		)
		(property "License" "Apache-2.0"
			(at 44.085 291.985 0)
			(layer "F.Fab")
			(hide yes)
			(effects
				(font
					(size 1 1)
					(thickness 0.15)
				)
			)
		)
		(property "MPN" "ESD9X5.0ST5G"
			(at 44.085 291.985 0)
			(layer "F.Fab")
			(hide yes)
			(effects
				(font
					(size 1 1)
					(thickness 0.15)
				)
			)
		)
		(property "Manufacturer" "ON Semiconductor"
			(at 44.085 291.985 0)
			(layer "F.Fab")
			(hide yes)
			(effects
				(font
					(size 1 1)
					(thickness 0.15)
				)
			)
		)
		(property "Public" "False"
			(at 44.085 291.985 0)
			(layer "F.Fab")
			(hide yes)
			(effects
				(font
					(size 1 1)
					(thickness 0.15)
				)
			)
		)
		(sheetfile "environment-sensor.kicad_sch")
		(attr smd)
		(fp_line
			(start -0.5 0.4)
			(end 0.5 0.4)
			(stroke
				(width 0.15)
				(type solid)
			)
			(layer "F.SilkS")
		)
		(fp_line
			(start -0.5 0.4)
			(end -0.5 0.3)
			(stroke
				(width 0.15)
				(type solid)
			)
			(layer "F.SilkS")
		)
		(fp_line
			(start 0.5 0.4)
			(end 0.5 0.3)
			(stroke
				(width 0.15)
				(type solid)
			)
			(layer "F.SilkS")
		)
		(fp_line
			(start -0.5 -0.3)
			(end -0.5 -0.4)
			(stroke
				(width 0.15)
				(type solid)
			)
			(layer "F.SilkS")
		)
		(fp_line
			(start -0.5 -0.4)
			(end 0.5 -0.4)
			(stroke
				(width 0.15)
				(type solid)
			)
			(layer "F.SilkS")
		)
		(fp_line
			(start -0.16 -0.4)
			(end -0.16 0.4)
			(stroke
				(width 0.15)
				(type solid)
			)
			(layer "F.SilkS")
		)
		(fp_line
			(start 0.5 -0.4)
			(end 0.5 -0.3)
			(stroke
				(width 0.15)
				(type solid)
			)
			(layer "F.SilkS")
		)
		(fp_rect
			(start -0.68 -0.41)
			(end 0.68 0.41)
			(stroke
				(width 0.05)
				(type solid)
			)
			(fill no)
			(layer "F.CrtYd")
		)
		(fp_line
			(start -0.202 -0.3)
			(end -0.202 0.298)
			(stroke
				(width 0.15)
				(type solid)
			)
			(layer "F.Fab")
		)
		(fp_rect
			(start -0.402 -0.3)
			(end 0.4 0.298)
			(stroke
				(width 0.15)
				(type solid)
			)
			(fill no)
			(layer "F.Fab")
		)
		(fp_text user "${REFERENCE}"
			(at 0 1.1 270)
			(unlocked yes)
			(layer "F.Fab")
			(effects
				(font
					(size 1 1)
					(thickness 0.15)
				)
			)
		)
		(pad "1" smd roundrect
			(at -0.438 0 270)
			(size 0.4 0.325)
			(layers "F.Cu" "F.Mask" "F.Paste")
			(roundrect_rratio 0.25)
			(net 1 "GND")
			(pinfunction "C")
			(pintype "passive")
		)
		(pad "2" smd roundrect
			(at 0.436 0 270)
			(size 0.4 0.325)
			(layers "F.Cu" "F.Mask" "F.Paste")
			(roundrect_rratio 0.25)
			(net 27 "/VBUS")
			(pinfunction "A")
			(pintype "passive")
		)
	)
	(footprint "antmicro-footprints:C_0402_1005Metric"
		(layer "F.Cu")
		(at 172.6 136.15)
		(descr "Capacitor SMD 0402")
		(tags "capacitor SMD 0402")
		(property "Reference" "C8"
			(at 26.15 1.65 0)
			(layer "F.SilkS")
			(effects
				(font
					(size 0.7 0.7)
					(thickness 0.15)
				)
				(justify left bottom)
			)
		)
		(property "Value" "C_100n_0402"
			(at 0 1.4 0)
			(layer "F.Fab")
			(effects
				(font
					(size 0.7 0.7)
					(thickness 0.15)
				)
				(justify left bottom)
			)
		)
		(property "Description" "SMD Multilayer Ceramic Capacitor, 0.1 µF, 50 V, 0402 [1005 Metric], ± 10%, X5R, GRM Series"
			(at 0 0 0)
			(layer "F.Fab")
			(hide yes)
			(effects
				(font
					(size 1.27 1.27)
					(thickness 0.15)
				)
			)
		)
		(property "Author" "Antmicro"
			(at 0 0 0)
			(layer "F.Fab")
			(hide yes)
			(effects
				(font
					(size 1 1)
					(thickness 0.15)
				)
			)
		)
		(property "Dielectric" "X5R"
			(at 0 0 0)
			(layer "F.Fab")
			(hide yes)
			(effects
				(font
					(size 1 1)
					(thickness 0.15)
				)
			)
		)
		(property "License" "Apache-2.0"
			(at 0 0 0)
			(layer "F.Fab")
			(hide yes)
			(effects
				(font
					(size 1 1)
					(thickness 0.15)
				)
			)
		)
		(property "MPN" "GRM155R61H104KE14D"
			(at 0 0 0)
			(layer "F.Fab")
			(hide yes)
			(effects
				(font
					(size 1 1)
					(thickness 0.15)
				)
			)
		)
		(property "Manufacturer" "Murata"
			(at 0 0 0)
			(layer "F.Fab")
			(hide yes)
			(effects
				(font
					(size 1 1)
					(thickness 0.15)
				)
			)
		)
		(property "Public" "False"
			(at 0 0 0)
			(layer "F.Fab")
			(hide yes)
			(effects
				(font
					(size 1 1)
					(thickness 0.15)
				)
			)
		)
		(property "Val" "100n"
			(at 0 0 0)
			(layer "F.Fab")
			(hide yes)
			(effects
				(font
					(size 1 1)
					(thickness 0.15)
				)
			)
		)
		(property "Voltage" "50V"
			(at 0 0 0)
			(layer "F.Fab")
			(hide yes)
			(effects
				(font
					(size 1 1)
					(thickness 0.15)
				)
			)
		)
		(sheetfile "environment-sensor.kicad_sch")
		(attr smd)
		(fp_rect
			(start -0.925 -0.47)
			(end 0.925 0.47)
			(stroke
				(width 0.05)
				(type default)
			)
			(fill no)
			(layer "F.CrtYd")
		)
		(fp_line
			(start -0.494 -0.25)
			(end 0.504 -0.25)
			(stroke
				(width 0.15)
				(type solid)
			)
			(layer "F.Fab")
		)
		(fp_line
			(start -0.494 0.248)
			(end -0.494 -0.25)
			(stroke
				(width 0.15)
				(type solid)
			)
			(layer "F.Fab")
		)
		(fp_line
			(start 0.504 -0.25)
			(end 0.504 0.248)
			(stroke
				(width 0.15)
				(type solid)
			)
			(layer "F.Fab")
		)
		(fp_line
			(start 0.504 0.248)
			(end -0.494 0.248)
			(stroke
				(width 0.15)
				(type solid)
			)
			(layer "F.Fab")
		)
		(pad "1" smd roundrect
			(at -0.48 0)
			(size 0.59 0.64)
			(layers "F.Cu" "F.Mask" "F.Paste")
			(roundrect_rratio 0.25)
			(net 26 "+5V")
			(pintype "passive")
		)
		(pad "2" smd roundrect
			(at 0.48 0)
			(size 0.59 0.64)
			(layers "F.Cu" "F.Mask" "F.Paste")
			(roundrect_rratio 0.25)
			(net 1 "GND")
			(pintype "passive")
		)
	)
	(footprint "antmicro-footprints:MP_Pad5.4mm_Drill2.7mm"
		(layer "F.Cu")
		(at 163.55 117.05)
		(descr "Mounting Hole 2.7mm, M2.5")
		(tags "mounting hole 2.7mm m2.5")
		(property "Reference" "MP1"
			(at -3.5 -2.5 0)
			(layer "F.SilkS")
			(effects
				(font
					(size 0.7 0.7)
					(thickness 0.15)
				)
				(justify left bottom)
			)
		)
		(property "Value" "MP_Pad5.4mm_Drill2.7mm"
			(at 0 3.6 0)
			(layer "F.Fab")
			(effects
				(font
					(size 0.7 0.7)
					(thickness 0.15)
				)
				(justify left bottom)
			)
		)
		(property "Description" "Mechanical part"
			(at 0 0 0)
			(layer "F.Fab")
			(hide yes)
			(effects
				(font
					(size 1.27 1.27)
					(thickness 0.15)
				)
			)
		)
		(property "Author" "Antmicro"
			(at 0 0 0)
			(layer "F.Fab")
			(hide yes)
			(effects
				(font
					(size 1 1)
					(thickness 0.15)
				)
			)
		)
		(property "License" "Apache-2.0"
			(at 0 0 0)
			(layer "F.Fab")
			(hide yes)
			(effects
				(font
					(size 1 1)
					(thickness 0.15)
				)
			)
		)
		(property "Public" "False"
			(at 0 0 0)
			(layer "F.Fab")
			(hide yes)
			(effects
				(font
					(size 1 1)
					(thickness 0.15)
				)
			)
		)
		(sheetfile "environment-sensor.kicad_sch")
		(attr exclude_from_pos_files exclude_from_bom)
		(pad "1" thru_hole circle
			(at 0 0)
			(size 5.4 5.4)
			(drill 2.7)
			(layers "*.Cu" "*.Mask")
			(remove_unused_layers no)
			(net 22 "unconnected-(MP1-Pad1)")
			(pintype "passive+no_connect")
		)
	)
	(footprint "antmicro-footprints:TP_SMD_1.5mm"
		(locked yes)
		(layer "F.Cu")
		(at 183.5 116)
		(property "Reference" "TP5"
			(at -1.73 -1.079 0)
			(layer "F.SilkS")
			(hide yes)
			(effects
				(font
					(size 0.7 0.7)
					(thickness 0.15)
				)
				(justify left bottom)
			)
		)
		(property "Value" "TP_1.5mm_SMD"
			(at 0 1.7 0)
			(layer "F.Fab")
			(effects
				(font
					(size 0.7 0.7)
					(thickness 0.15)
				)
				(justify left bottom)
			)
		)
		(property "Description" "test point, SMT"
			(at 0 0 0)
			(layer "F.Fab")
			(hide yes)
			(effects
				(font
					(size 1.27 1.27)
					(thickness 0.15)
				)
			)
		)
		(property "Author" "Antmicro"
			(at 0 0 0)
			(layer "F.Fab")
			(hide yes)
			(effects
				(font
					(size 1 1)
					(thickness 0.15)
				)
			)
		)
		(property "License" "Apache-2.0"
			(at 0 0 0)
			(layer "F.Fab")
			(hide yes)
			(effects
				(font
					(size 1 1)
					(thickness 0.15)
				)
			)
		)
		(property "MPN" ""
			(at 0 0 0)
			(layer "F.Fab")
			(hide yes)
			(effects
				(font
					(size 1 1)
					(thickness 0.15)
				)
			)
		)
		(property "Manufacturer" ""
			(at 0 0 0)
			(layer "F.Fab")
			(hide yes)
			(effects
				(font
					(size 1 1)
					(thickness 0.15)
				)
			)
		)
		(property "Public" "False"
			(at 0 0 0)
			(layer "F.Fab")
			(hide yes)
			(effects
				(font
					(size 1 1)
					(thickness 0.15)
				)
			)
		)
		(sheetfile "environment-sensor.kicad_sch")
		(attr exclude_from_pos_files)
		(pad "1" smd circle
			(at 0 0 270)
			(size 1.5 1.5)
			(layers "F.Cu" "F.Mask")
			(net 19 "JTDO")
			(pinfunction "1")
			(pintype "passive")
		)
	)
	(footprint "antmicro-footprints:C_0402_1005Metric"
		(layer "F.Cu")
		(at 172.226 121.829 90)
		(descr "Capacitor SMD 0402")
		(tags "capacitor SMD 0402")
		(property "Reference" "C5"
			(at 0.936 -0.575 90)
			(layer "F.SilkS")
			(effects
				(font
					(size 0.7 0.7)
					(thickness 0.15)
				)
				(justify right bottom)
			)
		)
		(property "Value" "C_100n_0402"
			(at 0 1.4 90)
			(layer "F.Fab")
			(effects
				(font
					(size 0.7 0.7)
					(thickness 0.15)
				)
				(justify left bottom)
			)
		)
		(property "Description" "SMD Multilayer Ceramic Capacitor, 0.1 µF, 50 V, 0402 [1005 Metric], ± 10%, X5R, GRM Series"
			(at 0 0 90)
			(layer "F.Fab")
			(hide yes)
			(effects
				(font
					(size 1.27 1.27)
					(thickness 0.15)
				)
			)
		)
		(property "Author" "Antmicro"
			(at 294.055 -50.397 0)
			(layer "F.Fab")
			(hide yes)
			(effects
				(font
					(size 1 1)
					(thickness 0.15)
				)
			)
		)
		(property "Dielectric" "X5R"
			(at 294.055 -50.397 0)
			(layer "F.Fab")
			(hide yes)
			(effects
				(font
					(size 1 1)
					(thickness 0.15)
				)
			)
		)
		(property "License" "Apache-2.0"
			(at 294.055 -50.397 0)
			(layer "F.Fab")
			(hide yes)
			(effects
				(font
					(size 1 1)
					(thickness 0.15)
				)
			)
		)
		(property "MPN" "GRM155R61H104KE14D"
			(at 294.055 -50.397 0)
			(layer "F.Fab")
			(hide yes)
			(effects
				(font
					(size 1 1)
					(thickness 0.15)
				)
			)
		)
		(property "Manufacturer" "Murata"
			(at 294.055 -50.397 0)
			(layer "F.Fab")
			(hide yes)
			(effects
				(font
					(size 1 1)
					(thickness 0.15)
				)
			)
		)
		(property "Public" "False"
			(at 294.055 -50.397 0)
			(layer "F.Fab")
			(hide yes)
			(effects
				(font
					(size 1 1)
					(thickness 0.15)
				)
			)
		)
		(property "Val" "100n"
			(at 294.055 -50.397 0)
			(layer "F.Fab")
			(hide yes)
			(effects
				(font
					(size 1 1)
					(thickness 0.15)
				)
			)
		)
		(property "Voltage" "50V"
			(at 294.055 -50.397 0)
			(layer "F.Fab")
			(hide yes)
			(effects
				(font
					(size 1 1)
					(thickness 0.15)
				)
			)
		)
		(sheetfile "environment-sensor.kicad_sch")
		(attr smd)
		(fp_rect
			(start -0.925 -0.47)
			(end 0.925 0.47)
			(stroke
				(width 0.05)
				(type default)
			)
			(fill no)
			(layer "F.CrtYd")
		)
		(fp_line
			(start 0.504 -0.25)
			(end 0.504 0.248)
			(stroke
				(width 0.15)
				(type solid)
			)
			(layer "F.Fab")
		)
		(fp_line
			(start -0.494 -0.25)
			(end 0.504 -0.25)
			(stroke
				(width 0.15)
				(type solid)
			)
			(layer "F.Fab")
		)
		(fp_line
			(start 0.504 0.248)
			(end -0.494 0.248)
			(stroke
				(width 0.15)
				(type solid)
			)
			(layer "F.Fab")
		)
		(fp_line
			(start -0.494 0.248)
			(end -0.494 -0.25)
			(stroke
				(width 0.15)
				(type solid)
			)
			(layer "F.Fab")
		)
		(pad "1" smd roundrect
			(at -0.48 0 90)
			(size 0.59 0.64)
			(layers "F.Cu" "F.Mask" "F.Paste")
			(roundrect_rratio 0.25)
			(net 1 "GND")
			(pintype "passive")
		)
		(pad "2" smd roundrect
			(at 0.48 0 90)
			(size 0.59 0.64)
			(layers "F.Cu" "F.Mask" "F.Paste")
			(roundrect_rratio 0.25)
			(net 29 "Net-(U1-3V3OUT)")
			(pintype "passive")
		)
	)
	(footprint "antmicro-footprints:R_0402_1005Metric"
		(layer "F.Cu")
		(at 169.985 129.8)
		(descr "Resistor SMD 0402")
		(tags "resistor SMD 0402")
		(property "Reference" "R4"
			(at 0.915 0.4 0)
			(layer "F.SilkS")
			(effects
				(font
					(size 0.7 0.7)
					(thickness 0.15)
				)
				(justify left bottom)
			)
		)
		(property "Value" "R_5k1_0402"
			(at 0 1.4 0)
			(layer "F.Fab")
			(effects
				(font
					(size 0.7 0.7)
					(thickness 0.15)
				)
				(justify left bottom)
			)
		)
		(property "Description" "SMD Chip Resistor, 5.1 kohm, ± 1%, 63 mW, 0402 [1005 Metric], Thick Film, General Purpose"
			(at 0 0 0)
			(layer "F.Fab")
			(hide yes)
			(effects
				(font
					(size 1.27 1.27)
					(thickness 0.15)
				)
			)
		)
		(property "Author" "Antmicro"
			(at 0 0 0)
			(layer "F.Fab")
			(hide yes)
			(effects
				(font
					(size 1 1)
					(thickness 0.15)
				)
			)
		)
		(property "License" "Apache-2.0"
			(at 0 0 0)
			(layer "F.Fab")
			(hide yes)
			(effects
				(font
					(size 1 1)
					(thickness 0.15)
				)
			)
		)
		(property "MPN" "CR0402-FX-5101GLF"
			(at 0 0 0)
			(layer "F.Fab")
			(hide yes)
			(effects
				(font
					(size 1 1)
					(thickness 0.15)
				)
			)
		)
		(property "Manufacturer" "Bourns"
			(at 0 0 0)
			(layer "F.Fab")
			(hide yes)
			(effects
				(font
					(size 1 1)
					(thickness 0.15)
				)
			)
		)
		(property "Public" "False"
			(at 0 0 0)
			(layer "F.Fab")
			(hide yes)
			(effects
				(font
					(size 1 1)
					(thickness 0.15)
				)
			)
		)
		(property "Tolerance" "1%"
			(at 0 0 0)
			(layer "F.Fab")
			(hide yes)
			(effects
				(font
					(size 1 1)
					(thickness 0.15)
				)
			)
		)
		(property "Val" "5k1"
			(at 0 0 0)
			(layer "F.Fab")
			(hide yes)
			(effects
				(font
					(size 1 1)
					(thickness 0.15)
				)
			)
		)
		(sheetfile "environment-sensor.kicad_sch")
		(attr smd)
		(fp_rect
			(start -0.925 -0.47)
			(end 0.925 0.47)
			(stroke
				(width 0.05)
				(type default)
			)
			(fill no)
			(layer "F.CrtYd")
		)
		(fp_rect
			(start -0.5 -0.25)
			(end 0.5 0.25)
			(stroke
				(width 0.15)
				(type solid)
			)
			(fill no)
			(layer "F.Fab")
		)
		(pad "1" smd roundrect
			(at -0.48 0)
			(size 0.59 0.64)
			(layers "F.Cu" "F.Mask" "F.Paste")
			(roundrect_rratio 0.25)
			(net 1 "GND")
			(pintype "passive")
		)
		(pad "2" smd roundrect
			(at 0.48 0)
			(size 0.59 0.64)
			(layers "F.Cu" "F.Mask" "F.Paste")
			(roundrect_rratio 0.25)
			(net 5 "/USB_CC2")
			(pintype "passive")
		)
	)
)
